(kicad_pcb
	(version 20260206)
	(generator "pcbnew")
	(generator_version "10.0")
	(general
		(thickness 1.6)
		(legacy_teardrops no)
	)
	(paper "A4")
	(title_block
		(title "04192023_DAF0TMB3IC0_F0TG_MB_C_brd_V02_OCP.brd")
		(comment 1 "Grand Teton / footprints 3543-3547 of 8354")
	)
	(layers
		(0 "F.Cu" signal "TOP")
		(4 "In1.Cu" signal "GND")
		(6 "In2.Cu" signal "IN1")
		(8 "In3.Cu" signal "GND1")
		(10 "In4.Cu" signal "IN2")
		(12 "In5.Cu" signal "GND2")
		(14 "In6.Cu" signal "IN3")
		(16 "In7.Cu" signal "GND3")
		(18 "In8.Cu" signal "VCC")
		(20 "In9.Cu" signal "VCC1")
		(22 "In10.Cu" signal "GND4")
		(24 "In11.Cu" signal "IN4")
		(26 "In12.Cu" signal "GND5")
		(28 "In13.Cu" signal "IN5")
		(30 "In14.Cu" signal "GND6")
		(32 "In15.Cu" signal "IN6")
		(34 "In16.Cu" signal "GND7")
		(2 "B.Cu" signal "BOTTOM")
		(9 "F.Adhes" user "F.Adhesive")
		(11 "B.Adhes" user "B.Adhesive")
		(13 "F.Paste" user "Package Geometry/Pastemask Top")
		(15 "B.Paste" user "Package Geometry/Pastemask Bottom")
		(5 "F.SilkS" user "Ref Des/Silkscreen Top")
		(7 "B.SilkS" user "Ref Des/Silkscreen Bottom")
		(1 "F.Mask" user "Board Geometry/Soldermask Top")
		(3 "B.Mask" user "Board Geometry/Soldermask Bottom")
		(17 "Dwgs.User" user "User.Drawings")
		(19 "Cmts.User" user "User.Comments")
		(21 "Eco1.User" user "User.Eco1")
		(23 "Eco2.User" user "User.Eco2")
		(25 "Edge.Cuts" user "Board Geometry/Outline")
		(27 "Margin" user)
		(31 "F.CrtYd" user "Package Geometry/Place Bound Top")
		(29 "B.CrtYd" user "Package Geometry/Place Bound Bottom")
		(35 "F.Fab" user "Ref Des/Assembly Top")
		(33 "B.Fab" user "Ref Des/Assembly Bottom")
	)
	(footprint ""
		(layer "F.Cu")
		(at 414.529778 -163.76777 180)
		(property "Reference" "PU51"
			(at 5.373624 -4.878324 0)
			(unlocked yes)
			(layer "F.SilkS")
			(effects
				(font
					(size 0.7874 0.5842)
					(thickness 0.1524)
				)
				(justify left)
			)
		)
		(property "Value" ""
			(at 0 0 180)
			(layer "F.Fab")
			(effects
				(font
					(size 1.27 1.27)
				)
			)
		)
		(duplicate_pad_numbers_are_jumpers no)
		(fp_line
			(start 2.500122 2.999994)
			(end 2.2987 2.999994)
			(stroke
				(width 0.1524)
				(type default)
			)
			(layer "F.SilkS")
		)
		(fp_line
			(start 2.500122 2.339594)
			(end 2.500122 2.999994)
			(stroke
				(width 0.1524)
				(type default)
			)
			(layer "F.SilkS")
		)
		(fp_line
			(start 2.500122 -2.999994)
			(end 2.500122 -2.44348)
			(stroke
				(width 0.1524)
				(type default)
			)
			(layer "F.SilkS")
		)
		(fp_line
			(start 2.31394 -2.999994)
			(end 2.500122 -2.999994)
			(stroke
				(width 0.1524)
				(type default)
			)
			(layer "F.SilkS")
		)
		(fp_line
			(start -2.2987 2.999994)
			(end -2.500122 2.999994)
			(stroke
				(width 0.1524)
				(type default)
			)
			(layer "F.SilkS")
		)
		(fp_line
			(start -2.500122 2.999994)
			(end -2.500122 2.339594)
			(stroke
				(width 0.1524)
				(type default)
			)
			(layer "F.SilkS")
		)
		(fp_line
			(start -2.500122 0.6604)
			(end -2.500122 0.229108)
			(stroke
				(width 0.1524)
				(type default)
			)
			(layer "F.SilkS")
		)
		(fp_line
			(start -2.500122 -2.529078)
			(end -2.500122 -2.999994)
			(stroke
				(width 0.1524)
				(type default)
			)
			(layer "F.SilkS")
		)
		(fp_line
			(start -2.500122 -2.999994)
			(end -2.24409 -2.999994)
			(stroke
				(width 0.1524)
				(type default)
			)
			(layer "F.SilkS")
		)
		(fp_poly
			(pts
				(xy -2.637028 -2.515362) (xy -3.35026 -2.753106) (xy -2.874518 -3.228594)
			)
			(stroke
				(width 0)
				(type default)
			)
			(fill yes)
			(layer "F.SilkS")
		)
		(fp_line
			(start 2.500122 2.999994)
			(end -2.500122 2.999994)
			(stroke
				(width 0.1)
				(type default)
			)
			(layer "F.Fab")
		)
		(fp_line
			(start 2.500122 -2.999994)
			(end 2.500122 2.999994)
			(stroke
				(width 0.1)
				(type default)
			)
			(layer "F.Fab")
		)
		(fp_line
			(start -2.500122 2.999994)
			(end -2.500122 -2.999994)
			(stroke
				(width 0.1)
				(type default)
			)
			(layer "F.Fab")
		)
		(fp_line
			(start -2.500122 -2.999994)
			(end 2.500122 -2.999994)
			(stroke
				(width 0.1)
				(type default)
			)
			(layer "F.Fab")
		)
		(fp_poly
			(pts
				(xy -4.218432 -2.783078) (xy -4.218432 -1.767078) (xy -3.202432 -2.275078)
			)
			(stroke
				(width 0)
				(type default)
			)
			(fill yes)
			(layer "F.Fab")
		)
		(pad "1" smd rect
			(at -2.400046 -2.275078 270)
			(size 0.2286 0.6096)
			(layers "F.Cu" "F.Mask" "F.Paste")
			(net "PVDDCR_SOC_P0_VOS3")
		)
		(pad "2" smd rect
			(at -2.400046 -1.82499 270)
			(size 0.2286 0.6096)
			(layers "F.Cu" "F.Mask" "F.Paste")
			(net "GND")
		)
		(pad "3" smd rect
			(at -2.400046 -1.374902 270)
			(size 0.2286 0.6096)
			(layers "F.Cu" "F.Mask" "F.Paste")
			(net "PVDDCR_SOC_P0_VCC3")
		)
		(pad "4" smd rect
			(at -2.400046 -0.925068 270)
			(size 0.2286 0.6096)
			(layers "F.Cu" "F.Mask" "F.Paste")
			(net "PVDDCR_CPU0_P0_PVCC")
		)
		(pad "5" smd rect
			(at -2.400046 -0.47498 270)
			(size 0.2286 0.6096)
			(layers "F.Cu" "F.Mask" "F.Paste")
			(net "GND")
		)
		(pad "6" smd rect
			(at -2.400046 -0.024892 270)
			(size 0.2286 0.6096)
			(layers "F.Cu" "F.Mask" "F.Paste")
			(net "NC_PVDDCR_SOC_P0_GL1_3")
		)
		(pad "7_9-20_24" smd circle
			(at 0 1.150112 270)
			(size 0 0)
			(layers "F.Cu" "F.Mask" "F.Paste")
			(net "GND")
		)
		(pad "10_19" smd rect
			(at 0 2.899918 270)
			(size 0.6096 4.318)
			(layers "F.Cu" "F.Mask" "F.Paste")
			(net "SW_PVDDCR_SOC_P0_SW3")
		)
		(pad "25_29" smd rect
			(at 1.549908 -1.279906 90)
			(size 2.0574 2.3114)
			(layers "F.Cu" "F.Mask" "F.Paste")
			(net "SW_P12V_AUX_PVDDCR_SOC_P0_FLT")
		)
		(pad "30" smd rect
			(at 2.05994 -2.899918 180)
			(size 0.2286 0.6096)
			(layers "F.Cu" "F.Mask" "F.Paste")
			(net "SW_P12V_AUX_PVDDCR_SOC_P0_FLT")
		)
		(pad "31" smd rect
			(at 1.610106 -2.899918 180)
			(size 0.2286 0.6096)
			(layers "F.Cu" "F.Mask" "F.Paste")
			(net "NC_PVDDCR_SOC_P0_DNC3")
		)
		(pad "32" smd rect
			(at 1.160018 -2.899918 180)
			(size 0.2286 0.6096)
			(layers "F.Cu" "F.Mask" "F.Paste")
			(net "SW_PVDDCR_SOC_P0_PH3")
		)
		(pad "33" smd rect
			(at 0.70993 -2.899918 180)
			(size 0.2286 0.6096)
			(layers "F.Cu" "F.Mask" "F.Paste")
			(net "SW_PVDDCR_SOC_P0_BOOT3")
		)
		(pad "34" smd rect
			(at 0.260096 -2.899918 180)
			(size 0.2286 0.6096)
			(layers "F.Cu" "F.Mask" "F.Paste")
			(net "PVDDCR_SOC_P0_PWM3")
		)
		(pad "35" smd rect
			(at -0.189992 -2.899918 180)
			(size 0.2286 0.6096)
			(layers "F.Cu" "F.Mask" "F.Paste")
			(net "PVDDCR_SOC_P0_VCC3")
		)
		(pad "36" smd rect
			(at -0.64008 -2.899918 180)
			(size 0.2286 0.6096)
			(layers "F.Cu" "F.Mask" "F.Paste")
			(net "PVDDCR_SOC_P0_TEMP1")
		)
		(pad "37" smd rect
			(at -1.089914 -2.899918 180)
			(size 0.2286 0.6096)
			(layers "F.Cu" "F.Mask" "F.Paste")
			(net "PVDDCR_SOC_P0_LSET3")
		)
		(pad "38" smd rect
			(at -1.540002 -2.899918 180)
			(size 0.2286 0.6096)
			(layers "F.Cu" "F.Mask" "F.Paste")
			(net "PVDDCR_SOC_P0_IMON3")
		)
		(pad "39" smd rect
			(at -1.99009 -2.899918 180)
			(size 0.2286 0.6096)
			(layers "F.Cu" "F.Mask" "F.Paste")
			(net "PVDDCR_CPU0_P0_VCCS")
		)
		(pad "40" smd rect
			(at -0.87503 -1.27508 180)
			(size 1.7526 1.9558)
			(layers "F.Cu" "F.Mask" "F.Paste")
			(net "GND")
		)
		(pad "41" smd rect
			(at -1.525016 0.249936 90)
			(size 0.3048 0.4572)
			(layers "F.Cu" "F.Mask" "F.Paste")
			(net "NC_PVDDCR_SOC_P0_GL2_3")
		)
		(zone
			(layer "F.Cu")
			(hatch none 0.5)
			(connect_pads
				(clearance 0)
			)
			(min_thickness 0.25)
			(keepout
				(tracks not_allowed)
				(vias allowed)
				(pads allowed)
				(copperpour not_allowed)
				(footprints allowed)
			)
			(placement
				(enabled no)
				(sheetname "")
			)
			(fill
				(thermal_gap 0.5)
				(thermal_bridge_width 0.5)
				(island_removal_mode 0)
			)
			(polygon
				(pts
					(xy 417.0299 -166.345108) (xy 417.0299 -166.018464) (xy 412.029656 -166.018464) (xy 412.029656 -166.331646)
					(xy 412.319978 -166.331646) (xy 412.319978 -166.312088) (xy 416.739578 -166.312088) (xy 416.739578 -166.345108)
				)
			)
		)
		(zone
			(layer "F.Cu")
			(hatch none 0.5)
			(connect_pads
				(clearance 0)
			)
			(min_thickness 0.25)
			(keepout
				(tracks not_allowed)
				(vias allowed)
				(pads allowed)
				(copperpour not_allowed)
				(footprints allowed)
			)
			(placement
				(enabled no)
				(sheetname "")
			)
			(fill
				(thermal_gap 0.5)
				(thermal_bridge_width 0.5)
				(island_removal_mode 0)
			)
			(polygon
				(pts
					(xy 414.477708 -163.52139) (xy 414.477708 -161.46399) (xy 416.331908 -161.46399) (xy 416.331908 -161.705036)
					(xy 416.574224 -161.705036) (xy 416.574224 -161.223452) (xy 412.722822 -161.223452) (xy 412.722822 -161.408364)
					(xy 414.18637 -161.408364) (xy 414.18637 -163.567364) (xy 412.029656 -163.567364) (xy 412.029656 -163.817046)
					(xy 414.182052 -163.817046)
				)
			)
		)
	)
	(footprint ""
		(layer "F.Cu")
		(at 259.070094 -141.968728 90)
		(property "Reference" "R604"
			(at 0 0 90)
			(layer "F.SilkS")
			(hide yes)
			(effects
				(font
					(size 1.27 1.27)
				)
			)
		)
		(property "Value" ""
			(at 0 0 90)
			(layer "F.Fab")
			(effects
				(font
					(size 1.27 1.27)
				)
			)
		)
		(duplicate_pad_numbers_are_jumpers no)
		(fp_line
			(start 0.7874 -0.4064)
			(end 0.7874 0.4064)
			(stroke
				(width 0.1524)
				(type default)
			)
			(layer "F.SilkS")
		)
		(fp_line
			(start -0.7874 -0.4064)
			(end 0.7874 -0.4064)
			(stroke
				(width 0.1524)
				(type default)
			)
			(layer "F.SilkS")
		)
		(fp_line
			(start 0.7874 0.4064)
			(end -0.7874 0.4064)
			(stroke
				(width 0.1524)
				(type default)
			)
			(layer "F.SilkS")
		)
		(fp_line
			(start -0.7874 0.4064)
			(end -0.7874 -0.4064)
			(stroke
				(width 0.1524)
				(type default)
			)
			(layer "F.SilkS")
		)
		(fp_line
			(start -0.12065 -0.305054)
			(end -0.12065 -0.2794)
			(stroke
				(width 0.1)
				(type default)
			)
			(layer "F.Fab")
		)
		(fp_line
			(start -0.67945 -0.305054)
			(end -0.12065 -0.305054)
			(stroke
				(width 0.1)
				(type default)
			)
			(layer "F.Fab")
		)
		(fp_line
			(start 0.67945 -0.3048)
			(end 0.67945 0.3048)
			(stroke
				(width 0.1)
				(type default)
			)
			(layer "F.Fab")
		)
		(fp_line
			(start 0.12065 -0.3048)
			(end 0.67945 -0.3048)
			(stroke
				(width 0.1)
				(type default)
			)
			(layer "F.Fab")
		)
		(fp_line
			(start 0.12065 -0.2794)
			(end 0.12065 -0.3048)
			(stroke
				(width 0.1)
				(type default)
			)
			(layer "F.Fab")
		)
		(fp_line
			(start -0.12065 -0.2794)
			(end 0.12065 -0.2794)
			(stroke
				(width 0.1)
				(type default)
			)
			(layer "F.Fab")
		)
		(fp_line
			(start 0.120396 0.2794)
			(end -0.12065 0.2794)
			(stroke
				(width 0.1)
				(type default)
			)
			(layer "F.Fab")
		)
		(fp_line
			(start -0.12065 0.2794)
			(end -0.12065 0.3048)
			(stroke
				(width 0.1)
				(type default)
			)
			(layer "F.Fab")
		)
		(fp_line
			(start 0.67945 0.3048)
			(end 0.120396 0.3048)
			(stroke
				(width 0.1)
				(type default)
			)
			(layer "F.Fab")
		)
		(fp_line
			(start 0.120396 0.3048)
			(end 0.120396 0.2794)
			(stroke
				(width 0.1)
				(type default)
			)
			(layer "F.Fab")
		)
		(fp_line
			(start -0.12065 0.3048)
			(end -0.67945 0.3048)
			(stroke
				(width 0.1)
				(type default)
			)
			(layer "F.Fab")
		)
		(fp_line
			(start -0.67945 0.3048)
			(end -0.67945 -0.305054)
			(stroke
				(width 0.1)
				(type default)
			)
			(layer "F.Fab")
		)
		(pad "1" smd circle
			(at -0.40005 0 90)
			(size 0 0)
			(layers "F.Cu" "F.Mask" "F.Paste")
			(net "SPI_CPU0_LVC3_D0")
		)
		(pad "2" smd circle
			(at 0.40005 0 90)
			(size 0 0)
			(layers "F.Cu" "F.Mask" "F.Paste")
			(net "SPI_CPU0_LVC3_SCM_D0")
		)
	)
	(footprint ""
		(layer "F.Cu")
		(at 185.49874 -133.548882 -90)
		(property "Reference" "R219"
			(at 0 0 270)
			(layer "F.SilkS")
			(hide yes)
			(effects
				(font
					(size 1.27 1.27)
				)
			)
		)
		(property "Value" ""
			(at 0 0 270)
			(layer "F.Fab")
			(effects
				(font
					(size 1.27 1.27)
				)
			)
		)
		(duplicate_pad_numbers_are_jumpers no)
		(fp_line
			(start -0.7874 0.4064)
			(end -0.7874 -0.4064)
			(stroke
				(width 0.1524)
				(type default)
			)
			(layer "F.SilkS")
		)
		(fp_line
			(start 0.7874 0.4064)
			(end -0.7874 0.4064)
			(stroke
				(width 0.1524)
				(type default)
			)
			(layer "F.SilkS")
		)
		(fp_line
			(start -0.7874 -0.4064)
			(end 0.7874 -0.4064)
			(stroke
				(width 0.1524)
				(type default)
			)
			(layer "F.SilkS")
		)
		(fp_line
			(start 0.7874 -0.4064)
			(end 0.7874 0.4064)
			(stroke
				(width 0.1524)
				(type default)
			)
			(layer "F.SilkS")
		)
		(fp_line
			(start -0.67945 0.3048)
			(end -0.67945 -0.305054)
			(stroke
				(width 0.1)
				(type default)
			)
			(layer "F.Fab")
		)
		(fp_line
			(start -0.12065 0.3048)
			(end -0.67945 0.3048)
			(stroke
				(width 0.1)
				(type default)
			)
			(layer "F.Fab")
		)
		(fp_line
			(start 0.120396 0.3048)
			(end 0.120396 0.2794)
			(stroke
				(width 0.1)
				(type default)
			)
			(layer "F.Fab")
		)
		(fp_line
			(start 0.67945 0.3048)
			(end 0.120396 0.3048)
			(stroke
				(width 0.1)
				(type default)
			)
			(layer "F.Fab")
		)
		(fp_line
			(start -0.12065 0.2794)
			(end -0.12065 0.3048)
			(stroke
				(width 0.1)
				(type default)
			)
			(layer "F.Fab")
		)
		(fp_line
			(start 0.120396 0.2794)
			(end -0.12065 0.2794)
			(stroke
				(width 0.1)
				(type default)
			)
			(layer "F.Fab")
		)
		(fp_line
			(start -0.12065 -0.2794)
			(end 0.12065 -0.2794)
			(stroke
				(width 0.1)
				(type default)
			)
			(layer "F.Fab")
		)
		(fp_line
			(start 0.12065 -0.2794)
			(end 0.12065 -0.3048)
			(stroke
				(width 0.1)
				(type default)
			)
			(layer "F.Fab")
		)
		(fp_line
			(start 0.12065 -0.3048)
			(end 0.67945 -0.3048)
			(stroke
				(width 0.1)
				(type default)
			)
			(layer "F.Fab")
		)
		(fp_line
			(start 0.67945 -0.3048)
			(end 0.67945 0.3048)
			(stroke
				(width 0.1)
				(type default)
			)
			(layer "F.Fab")
		)
		(fp_line
			(start -0.67945 -0.305054)
			(end -0.12065 -0.305054)
			(stroke
				(width 0.1)
				(type default)
			)
			(layer "F.Fab")
		)
		(fp_line
			(start -0.12065 -0.305054)
			(end -0.12065 -0.2794)
			(stroke
				(width 0.1)
				(type default)
			)
			(layer "F.Fab")
		)
		(pad "1" smd circle
			(at -0.40005 0 270)
			(size 0 0)
			(layers "F.Cu" "F.Mask" "F.Paste")
			(net "CPU0_NMI_SYNC_FLOOD_N")
		)
		(pad "2" smd circle
			(at 0.40005 0 270)
			(size 0 0)
			(layers "F.Cu" "F.Mask" "F.Paste")
			(net "FM_CPU0_NMI_SYNC_FLOOD_N")
		)
	)
	(footprint ""
		(layer "F.Cu")
		(at 102.6668 -396.6972 90)
		(property "Reference" "R673"
			(at 0 0 90)
			(layer "F.SilkS")
			(hide yes)
			(effects
				(font
					(size 1.27 1.27)
				)
			)
		)
		(property "Value" ""
			(at 0 0 90)
			(layer "F.Fab")
			(effects
				(font
					(size 1.27 1.27)
				)
			)
		)
		(duplicate_pad_numbers_are_jumpers no)
		(fp_line
			(start 0.32512 -0.175006)
			(end 0.32512 0.175006)
			(stroke
				(width 0.1)
				(type default)
			)
			(layer "F.Fab")
		)
		(fp_line
			(start -0.32512 -0.175006)
			(end 0.32512 -0.175006)
			(stroke
				(width 0.1)
				(type default)
			)
			(layer "F.Fab")
		)
		(fp_line
			(start 0.32512 0.175006)
			(end -0.32512 0.175006)
			(stroke
				(width 0.1)
				(type default)
			)
			(layer "F.Fab")
		)
		(fp_line
			(start -0.32512 0.175006)
			(end -0.32512 -0.175006)
			(stroke
				(width 0.1)
				(type default)
			)
			(layer "F.Fab")
		)
		(pad "1" smd rect
			(at -0.2667 0 90)
			(size 0.3048 0.381)
			(layers "F.Cu" "F.Mask" "F.Paste")
			(net "SMB_RT_CPU1_P0_ROM_R_SDA")
		)
		(pad "2" smd rect
			(at 0.2667 0 270)
			(size 0.3048 0.381)
			(layers "F.Cu" "F.Mask" "F.Paste")
			(net "SMB_RT_CPU1_P0_ROM_SDA")
		)
	)
	(footprint ""
		(layer "F.Cu")
		(at 42.3672 -378.71654)
		(property "Reference" "R674"
			(at 0 0 0)
			(layer "F.SilkS")
			(hide yes)
			(effects
				(font
					(size 1.27 1.27)
				)
			)
		)
		(property "Value" ""
			(at 0 0 0)
			(layer "F.Fab")
			(effects
				(font
					(size 1.27 1.27)
				)
			)
		)
		(duplicate_pad_numbers_are_jumpers no)
		(fp_line
			(start -0.32512 -0.175006)
			(end 0.32512 -0.175006)
			(stroke
				(width 0.1)
				(type default)
			)
			(layer "F.Fab")
		)
		(fp_line
			(start -0.32512 0.175006)
			(end -0.32512 -0.175006)
			(stroke
				(width 0.1)
				(type default)
			)
			(layer "F.Fab")
		)
		(fp_line
			(start 0.32512 -0.175006)
			(end 0.32512 0.175006)
			(stroke
				(width 0.1)
				(type default)
			)
			(layer "F.Fab")
		)
		(fp_line
			(start 0.32512 0.175006)
			(end -0.32512 0.175006)
			(stroke
				(width 0.1)
				(type default)
			)
			(layer "F.Fab")
		)
		(pad "1" smd rect
			(at -0.2667 0)
			(size 0.3048 0.381)
			(layers "F.Cu" "F.Mask" "F.Paste")
			(net "SMB_RT_CPU1_P0_ROM_MUX_1D_SCL")
		)
		(pad "2" smd rect
			(at 0.2667 0 180)
			(size 0.3048 0.381)
			(layers "F.Cu" "F.Mask" "F.Paste")
			(net "SMB_RT_CPU1_P0_ROM_MUX_1D_R_SCL")
		)
	)
)
